(kicad_pcb
	(version 20260206)
	(generator "pcbnew")
	(generator_version "10.0")
	(general
		(thickness 1.6)
		(legacy_teardrops no)
	)
	(paper "A4")
	(title_block
		(title "04192023_DAF0TMB3IC0_F0TG_MB_C_brd_V02_OCP.brd")
		(comment 1 "Grand Teton / footprints 2361-2363 of 8354")
	)
	(layers
		(0 "F.Cu" signal "TOP")
		(4 "In1.Cu" signal "GND")
		(6 "In2.Cu" signal "IN1")
		(8 "In3.Cu" signal "GND1")
		(10 "In4.Cu" signal "IN2")
		(12 "In5.Cu" signal "GND2")
		(14 "In6.Cu" signal "IN3")
		(16 "In7.Cu" signal "GND3")
		(18 "In8.Cu" signal "VCC")
		(20 "In9.Cu" signal "VCC1")
		(22 "In10.Cu" signal "GND4")
		(24 "In11.Cu" signal "IN4")
		(26 "In12.Cu" signal "GND5")
		(28 "In13.Cu" signal "IN5")
		(30 "In14.Cu" signal "GND6")
		(32 "In15.Cu" signal "IN6")
		(34 "In16.Cu" signal "GND7")
		(2 "B.Cu" signal "BOTTOM")
		(9 "F.Adhes" user "F.Adhesive")
		(11 "B.Adhes" user "B.Adhesive")
		(13 "F.Paste" user "Package Geometry/Pastemask Top")
		(15 "B.Paste" user "Package Geometry/Pastemask Bottom")
		(5 "F.SilkS" user "Ref Des/Silkscreen Top")
		(7 "B.SilkS" user "Ref Des/Silkscreen Bottom")
		(1 "F.Mask" user "Board Geometry/Soldermask Top")
		(3 "B.Mask" user "Board Geometry/Soldermask Bottom")
		(17 "Dwgs.User" user "User.Drawings")
		(19 "Cmts.User" user "User.Comments")
		(21 "Eco1.User" user "User.Eco1")
		(23 "Eco2.User" user "User.Eco2")
		(25 "Edge.Cuts" user "Board Geometry/Outline")
		(27 "Margin" user)
		(31 "F.CrtYd" user "Package Geometry/Place Bound Top")
		(29 "B.CrtYd" user "Package Geometry/Place Bound Bottom")
		(35 "F.Fab" user "Ref Des/Assembly Top")
		(33 "B.Fab" user "Ref Des/Assembly Bottom")
	)
	(footprint ""
		(layer "F.Cu")
		(at 444.329566 -423.914824 -90)
		(property "Reference" "PU6502"
			(at -6.632956 -0.115824 0)
			(unlocked yes)
			(layer "F.SilkS")
			(effects
				(font
					(size 0.7874 0.5842)
					(thickness 0.1524)
				)
				(justify left)
			)
		)
		(property "Value" ""
			(at 0 0 270)
			(layer "F.Fab")
			(effects
				(font
					(size 1.27 1.27)
				)
			)
		)
		(duplicate_pad_numbers_are_jumpers no)
		(fp_line
			(start 1.778 3.6322)
			(end 1.778 2.8702)
			(stroke
				(width 0.1524)
				(type default)
			)
			(layer "F.SilkS")
		)
		(fp_line
			(start -0.2032 2.8829)
			(end -0.2032 3.2639)
			(stroke
				(width 0.1524)
				(type default)
			)
			(layer "F.SilkS")
		)
		(fp_line
			(start -2.500122 2.500122)
			(end -2.500122 2.018538)
			(stroke
				(width 0.1524)
				(type default)
			)
			(layer "F.SilkS")
		)
		(fp_line
			(start -2.015998 2.500122)
			(end -2.500122 2.500122)
			(stroke
				(width 0.1524)
				(type default)
			)
			(layer "F.SilkS")
		)
		(fp_line
			(start 2.500122 2.500122)
			(end 2.015998 2.500122)
			(stroke
				(width 0.1524)
				(type default)
			)
			(layer "F.SilkS")
		)
		(fp_line
			(start 2.500122 2.015998)
			(end 2.500122 2.500122)
			(stroke
				(width 0.1524)
				(type default)
			)
			(layer "F.SilkS")
		)
		(fp_line
			(start -3.6576 1.8034)
			(end -2.8956 1.8034)
			(stroke
				(width 0.1524)
				(type default)
			)
			(layer "F.SilkS")
		)
		(fp_line
			(start 2.8829 0.2032)
			(end 3.2639 0.2032)
			(stroke
				(width 0.1524)
				(type default)
			)
			(layer "F.SilkS")
		)
		(fp_line
			(start -3.2639 -0.1778)
			(end -2.8829 -0.1778)
			(stroke
				(width 0.1524)
				(type default)
			)
			(layer "F.SilkS")
		)
		(fp_line
			(start 2.8702 -1.778)
			(end 3.6322 -1.778)
			(stroke
				(width 0.1524)
				(type default)
			)
			(layer "F.SilkS")
		)
		(fp_line
			(start -2.500122 -2.015998)
			(end -2.500122 -2.500122)
			(stroke
				(width 0.1524)
				(type default)
			)
			(layer "F.SilkS")
		)
		(fp_line
			(start -2.500122 -2.500122)
			(end -2.015998 -2.500122)
			(stroke
				(width 0.1524)
				(type default)
			)
			(layer "F.SilkS")
		)
		(fp_line
			(start 2.015998 -2.500122)
			(end 2.500122 -2.500122)
			(stroke
				(width 0.1524)
				(type default)
			)
			(layer "F.SilkS")
		)
		(fp_line
			(start 2.500122 -2.500122)
			(end 2.500122 -2.015998)
			(stroke
				(width 0.1524)
				(type default)
			)
			(layer "F.SilkS")
		)
		(fp_line
			(start -1.8034 -2.8702)
			(end -1.8034 -3.6322)
			(stroke
				(width 0.1524)
				(type default)
			)
			(layer "F.SilkS")
		)
		(fp_line
			(start 0.1778 -3.2385)
			(end 0.1778 -2.8575)
			(stroke
				(width 0.1524)
				(type default)
			)
			(layer "F.SilkS")
		)
		(fp_poly
			(pts
				(xy -2.921 -1.800098) (xy -3.504184 -1.508506) (xy -3.504184 -2.09169)
			)
			(stroke
				(width 0)
				(type default)
			)
			(fill yes)
			(layer "F.SilkS")
		)
		(fp_line
			(start 1.778 3.6322)
			(end 1.778 2.8702)
			(stroke
				(width 0.1)
				(type default)
			)
			(layer "F.Fab")
		)
		(fp_line
			(start -0.2032 2.8829)
			(end -0.2032 3.2639)
			(stroke
				(width 0.1)
				(type default)
			)
			(layer "F.Fab")
		)
		(fp_line
			(start -2.500122 2.500122)
			(end -2.500122 -2.500122)
			(stroke
				(width 0.1)
				(type default)
			)
			(layer "F.Fab")
		)
		(fp_line
			(start 2.500122 2.500122)
			(end -2.500122 2.500122)
			(stroke
				(width 0.1)
				(type default)
			)
			(layer "F.Fab")
		)
		(fp_line
			(start -3.6576 1.8034)
			(end -2.8956 1.8034)
			(stroke
				(width 0.1)
				(type default)
			)
			(layer "F.Fab")
		)
		(fp_line
			(start 2.8829 0.2032)
			(end 3.2639 0.2032)
			(stroke
				(width 0.1)
				(type default)
			)
			(layer "F.Fab")
		)
		(fp_line
			(start -3.2639 -0.1778)
			(end -2.8829 -0.1778)
			(stroke
				(width 0.1)
				(type default)
			)
			(layer "F.Fab")
		)
		(fp_line
			(start 2.8702 -1.778)
			(end 3.6322 -1.778)
			(stroke
				(width 0.1)
				(type default)
			)
			(layer "F.Fab")
		)
		(fp_line
			(start -2.500122 -2.500122)
			(end 2.500122 -2.500122)
			(stroke
				(width 0.1)
				(type default)
			)
			(layer "F.Fab")
		)
		(fp_line
			(start 2.500122 -2.500122)
			(end 2.500122 2.500122)
			(stroke
				(width 0.1)
				(type default)
			)
			(layer "F.Fab")
		)
		(fp_line
			(start -1.8034 -2.8702)
			(end -1.8034 -3.6322)
			(stroke
				(width 0.1)
				(type default)
			)
			(layer "F.Fab")
		)
		(fp_line
			(start 0.1778 -3.2385)
			(end 0.1778 -2.8575)
			(stroke
				(width 0.1)
				(type default)
			)
			(layer "F.Fab")
		)
		(fp_poly
			(pts
				(xy -2.921 -1.800098) (xy -3.504184 -1.508506) (xy -3.504184 -2.09169)
			)
			(stroke
				(width 0)
				(type default)
			)
			(fill yes)
			(layer "F.Fab")
		)
		(fp_text user "20"
			(at 1.840484 4.009898 270)
			(unlocked yes)
			(layer "F.SilkS")
			(effects
				(font
					(size 0.635 0.4064)
					(thickness 0.1524)
				)
				(justify left)
			)
		)
		(fp_text user "11"
			(at -3.331972 3.750056 270)
			(unlocked yes)
			(layer "F.SilkS")
			(effects
				(font
					(size 0.635 0.4064)
					(thickness 0.1524)
				)
				(justify left)
			)
		)
		(fp_text user "10"
			(at -2.990342 2.17678 180)
			(unlocked yes)
			(layer "F.SilkS")
			(effects
				(font
					(size 0.635 0.4064)
					(thickness 0.1524)
				)
				(justify left)
			)
		)
		(fp_text user "21"
			(at 2.97053 2.045716 180)
			(unlocked yes)
			(layer "F.SilkS")
			(effects
				(font
					(size 0.635 0.4064)
					(thickness 0.1524)
				)
				(justify left)
			)
		)
		(fp_text user "40"
			(at -3.61569 -2.603754 270)
			(unlocked yes)
			(layer "F.SilkS")
			(effects
				(font
					(size 0.635 0.4064)
					(thickness 0.1524)
				)
				(justify left)
			)
		)
		(fp_text user "30"
			(at 3.223768 -3.0988 180)
			(unlocked yes)
			(layer "F.SilkS")
			(effects
				(font
					(size 0.635 0.4064)
					(thickness 0.1524)
				)
				(justify left)
			)
		)
		(fp_text user "31"
			(at 1.42494 -3.682746 270)
			(unlocked yes)
			(layer "F.SilkS")
			(effects
				(font
					(size 0.635 0.4064)
					(thickness 0.1524)
				)
				(justify left)
			)
		)
		(fp_text user "11"
			(at -2.8702 3.278632 270)
			(unlocked yes)
			(layer "F.Fab")
			(effects
				(font
					(size 0.635 0.4064)
					(thickness 0.1524)
				)
				(justify left)
			)
		)
		(fp_text user "20"
			(at 2.0828 3.253232 270)
			(unlocked yes)
			(layer "F.Fab")
			(effects
				(font
					(size 0.635 0.4064)
					(thickness 0.1524)
				)
				(justify left)
			)
		)
		(fp_text user "10"
			(at -3.253232 2.1336 180)
			(unlocked yes)
			(layer "F.Fab")
			(effects
				(font
					(size 0.635 0.4064)
					(thickness 0.1524)
				)
				(justify left)
			)
		)
		(fp_text user "21"
			(at 3.274568 1.8796 180)
			(unlocked yes)
			(layer "F.Fab")
			(effects
				(font
					(size 0.635 0.4064)
					(thickness 0.1524)
				)
				(justify left)
			)
		)
		(fp_text user "40"
			(at -3.2004 -3.096768 270)
			(unlocked yes)
			(layer "F.Fab")
			(effects
				(font
					(size 0.635 0.4064)
					(thickness 0.1524)
				)
				(justify left)
			)
		)
		(fp_text user "30"
			(at 3.223768 -3.0988 180)
			(unlocked yes)
			(layer "F.Fab")
			(effects
				(font
					(size 0.635 0.4064)
					(thickness 0.1524)
				)
				(justify left)
			)
		)
		(fp_text user "31"
			(at 1.8542 -3.172968 270)
			(unlocked yes)
			(layer "F.Fab")
			(effects
				(font
					(size 0.635 0.4064)
					(thickness 0.1524)
				)
				(justify left)
			)
		)
		(pad "1" smd rect
			(at -2.400046 -1.800098 180)
			(size 0.1778 0.6096)
			(layers "F.Cu" "F.Mask" "F.Paste")
			(net "NC_P0V9_RETIMER_CPU0_PWM8")
		)
		(pad "2" smd rect
			(at -2.400046 -1.400048 180)
			(size 0.1778 0.6096)
			(layers "F.Cu" "F.Mask" "F.Paste")
			(net "NC_P0V9_RETIMER_CPU0_PWM7")
		)
		(pad "3" smd rect
			(at -2.400046 -0.999998 180)
			(size 0.1778 0.6096)
			(layers "F.Cu" "F.Mask" "F.Paste")
			(net "NC_P0V9_RETIMER_CPU0_PWM6")
		)
		(pad "4" smd rect
			(at -2.400046 -0.599948 180)
			(size 0.1778 0.6096)
			(layers "F.Cu" "F.Mask" "F.Paste")
			(net "NC_P0V9_RETIMER_CPU0_PWM5")
		)
		(pad "5" smd rect
			(at -2.400046 -0.199898 180)
			(size 0.1778 0.6096)
			(layers "F.Cu" "F.Mask" "F.Paste")
			(net "NC_P0V9_RETIMER_CPU0_PWM4")
		)
		(pad "6" smd rect
			(at -2.400046 0.199898 180)
			(size 0.1778 0.6096)
			(layers "F.Cu" "F.Mask" "F.Paste")
			(net "NC_P0V9_RETIMER_CPU0_PWM3")
		)
		(pad "7" smd rect
			(at -2.400046 0.599948 180)
			(size 0.1778 0.6096)
			(layers "F.Cu" "F.Mask" "F.Paste")
			(net "P0V9_RETIMER_CPU0_PWM2")
		)
		(pad "8" smd rect
			(at -2.400046 0.999998 180)
			(size 0.1778 0.6096)
			(layers "F.Cu" "F.Mask" "F.Paste")
			(net "P0V9_RETIMER_CPU0_PWM1")
		)
		(pad "9" smd rect
			(at -2.400046 1.400048 180)
			(size 0.1778 0.6096)
			(layers "F.Cu" "F.Mask" "F.Paste")
			(net "P0V9_RETIMER_CPU0_PMSDA_R")
		)
		(pad "10" smd rect
			(at -2.400046 1.800098 180)
			(size 0.1778 0.6096)
			(layers "F.Cu" "F.Mask" "F.Paste")
			(net "P0V9_RETIMER_CPU0_PMSCL_R")
		)
		(pad "11" smd rect
			(at -1.800098 2.400046 270)
			(size 0.1778 0.6096)
			(layers "F.Cu" "F.Mask" "F.Paste")
			(net "TP_P0V9_RETIMER_CPU0_PMALERT")
		)
		(pad "12" smd rect
			(at -1.400048 2.400046 270)
			(size 0.1778 0.6096)
			(layers "F.Cu" "F.Mask" "F.Paste")
			(net "PWRGD_P0V9_RETIMER_CPU0_R")
		)
		(pad "13" smd rect
			(at -0.999998 2.400046 270)
			(size 0.1778 0.6096)
			(layers "F.Cu" "F.Mask" "F.Paste")
			(net "P0V9_RETIMER_CPU0_EN0_R")
		)
		(pad "14" smd rect
			(at -0.599948 2.400046 270)
			(size 0.1778 0.6096)
			(layers "F.Cu" "F.Mask" "F.Paste")
			(net "P0V9_RETIMER_CPU0_VRHOT")
		)
		(pad "15" smd rect
			(at -0.199898 2.400046 270)
			(size 0.1778 0.6096)
			(layers "F.Cu" "F.Mask" "F.Paste")
			(net "P0V9_RETIMER_CPU0_INALERT")
		)
		(pad "16" smd rect
			(at 0.199898 2.400046 270)
			(size 0.1778 0.6096)
			(layers "F.Cu" "F.Mask" "F.Paste")
			(net "NC_P0V9_RETIMER_CPU0_PG1")
		)
		(pad "17" smd rect
			(at 0.599948 2.400046 270)
			(size 0.1778 0.6096)
			(layers "F.Cu" "F.Mask" "F.Paste")
			(net "P0V9_RETIMER_CPU0_SVID_CLK")
		)
		(pad "18" smd rect
			(at 0.999998 2.400046 270)
			(size 0.1778 0.6096)
			(layers "F.Cu" "F.Mask" "F.Paste")
			(net "P0V9_RETIMER_CPU0_SVID_SDA")
		)
		(pad "19" smd rect
			(at 1.400048 2.400046 270)
			(size 0.1778 0.6096)
			(layers "F.Cu" "F.Mask" "F.Paste")
			(net "TP_P0V9_RETIMER_CPU0_SVID_ALERT_N")
		)
		(pad "20" smd rect
			(at 1.800098 2.400046 270)
			(size 0.1778 0.6096)
			(layers "F.Cu" "F.Mask" "F.Paste")
			(net "P0V9_RETIMER_CPU0_EN1_R")
		)
		(pad "21" smd rect
			(at 2.400046 1.800098 180)
			(size 0.1778 0.6096)
			(layers "F.Cu" "F.Mask" "F.Paste")
			(net "P0V9_RETIMER_CPU0_SENSE_R_P")
		)
		(pad "22" smd rect
			(at 2.400046 1.400048 180)
			(size 0.1778 0.6096)
			(layers "F.Cu" "F.Mask" "F.Paste")
			(net "P0V9_RETIMER_CPU0_SENSE_SH_N")
		)
		(pad "23" smd rect
			(at 2.400046 0.999998 180)
			(size 0.1778 0.6096)
			(layers "F.Cu" "F.Mask" "F.Paste")
			(net "P0V9_RETIMER_CPU0_IMON1")
		)
		(pad "24" smd rect
			(at 2.400046 0.599948 180)
			(size 0.1778 0.6096)
			(layers "F.Cu" "F.Mask" "F.Paste")
			(net "P0V9_RETIMER_CPU0_IMON2")
		)
		(pad "25" smd rect
			(at 2.400046 0.199898 180)
			(size 0.1778 0.6096)
			(layers "F.Cu" "F.Mask" "F.Paste")
			(net "NC_P0V9_RETIMER_CPU0_IMON3")
		)
		(pad "26" smd rect
			(at 2.400046 -0.199898 180)
			(size 0.1778 0.6096)
			(layers "F.Cu" "F.Mask" "F.Paste")
			(net "NC_P0V9_RETIMER_CPU0_IMON4")
		)
		(pad "27" smd rect
			(at 2.400046 -0.599948 180)
			(size 0.1778 0.6096)
			(layers "F.Cu" "F.Mask" "F.Paste")
			(net "NC_P0V9_RETIMER_CPU0_IMON5")
		)
		(pad "28" smd rect
			(at 2.400046 -0.999998 180)
			(size 0.1778 0.6096)
			(layers "F.Cu" "F.Mask" "F.Paste")
			(net "NC_P0V9_RETIMER_CPU0_IMON6")
		)
		(pad "29" smd rect
			(at 2.400046 -1.400048 180)
			(size 0.1778 0.6096)
			(layers "F.Cu" "F.Mask" "F.Paste")
			(net "NC_P0V9_RETIMER_CPU0_IMON7")
		)
		(pad "30" smd rect
			(at 2.400046 -1.800098 180)
			(size 0.1778 0.6096)
			(layers "F.Cu" "F.Mask" "F.Paste")
			(net "NC_P0V9_RETIMER_CPU0_IMON8")
		)
		(pad "31" smd rect
			(at 1.800098 -2.400046 270)
			(size 0.1778 0.6096)
			(layers "F.Cu" "F.Mask" "F.Paste")
			(net "GND")
		)
		(pad "32" smd rect
			(at 1.400048 -2.400046 270)
			(size 0.1778 0.6096)
			(layers "F.Cu" "F.Mask" "F.Paste")
			(net "GND")
		)
		(pad "33" smd rect
			(at 0.999998 -2.400046 270)
			(size 0.1778 0.6096)
			(layers "F.Cu" "F.Mask" "F.Paste")
			(net "P0V9_RETIMER_CPU0_CFP")
		)
		(pad "34" smd rect
			(at 0.599948 -2.400046 270)
			(size 0.1778 0.6096)
			(layers "F.Cu" "F.Mask" "F.Paste")
			(net "P0V9_RETIMER_CPU0_ADDR")
		)
		(pad "35" smd rect
			(at 0.199898 -2.400046 270)
			(size 0.1778 0.6096)
			(layers "F.Cu" "F.Mask" "F.Paste")
			(net "P0V9_RETIMER_CPU0_TEMP0")
		)
		(pad "36" smd rect
			(at -0.199898 -2.400046 270)
			(size 0.1778 0.6096)
			(layers "F.Cu" "F.Mask" "F.Paste")
			(net "P0V9_RETIMER_CPU0_TEMP1_R")
		)
		(pad "37" smd rect
			(at -0.599948 -2.400046 270)
			(size 0.1778 0.6096)
			(layers "F.Cu" "F.Mask" "F.Paste")
			(net "P0V9_RETIMER_CPU0_VMON")
		)
		(pad "38" smd rect
			(at -0.999998 -2.400046 270)
			(size 0.1778 0.6096)
			(layers "F.Cu" "F.Mask" "F.Paste")
			(net "P0V9_RETIMER_CPU0_VINSEN")
		)
		(pad "39" smd rect
			(at -1.400048 -2.400046 270)
			(size 0.1778 0.6096)
			(layers "F.Cu" "F.Mask" "F.Paste")
			(net "P0V9_RETIMER_CPU0_VCC")
		)
		(pad "40" smd rect
			(at -1.800098 -2.400046 270)
			(size 0.1778 0.6096)
			(layers "F.Cu" "F.Mask" "F.Paste")
			(net "PV09_RETIMER_CPU0_VCCS")
		)
		(pad "TH" smd rect
			(at 0 0 270)
			(size 3.6576 3.6576)
			(layers "F.Cu" "F.Mask" "F.Paste")
			(net "GND")
		)
		(zone
			(layer "F.Cu")
			(hatch none 0.5)
			(connect_pads
				(clearance 0)
			)
			(min_thickness 0.25)
			(keepout
				(tracks not_allowed)
				(vias allowed)
				(pads allowed)
				(copperpour not_allowed)
				(footprints allowed)
			)
			(placement
				(enabled no)
				(sheetname "")
			)
			(fill
				(thermal_gap 0.5)
				(thermal_bridge_width 0.5)
				(island_removal_mode 0)
			)
			(polygon
				(pts
					(xy 446.361566 -425.946824) (xy 446.361566 -421.882824) (xy 442.297566 -421.882824) (xy 442.297566 -425.946824)
					(xy 446.183766 -425.946824) (xy 446.183766 -425.794424) (xy 442.449966 -425.794424) (xy 442.449966 -422.035224)
					(xy 446.209166 -422.035224) (xy 446.209166 -425.946824)
				)
			)
		)
	)
	(footprint ""
		(layer "F.Cu")
		(at 42.989754 -373.03583 -90)
		(property "Reference" "C833"
			(at 0 0 270)
			(layer "F.SilkS")
			(hide yes)
			(effects
				(font
					(size 1.27 1.27)
				)
			)
		)
		(property "Value" ""
			(at 0 0 270)
			(layer "F.Fab")
			(effects
				(font
					(size 1.27 1.27)
				)
			)
		)
		(duplicate_pad_numbers_are_jumpers no)
		(fp_line
			(start -0.299974 0.150114)
			(end -0.299974 -0.150114)
			(stroke
				(width 0.1)
				(type default)
			)
			(layer "F.Fab")
		)
		(fp_line
			(start 0.299974 0.150114)
			(end -0.299974 0.150114)
			(stroke
				(width 0.1)
				(type default)
			)
			(layer "F.Fab")
		)
		(fp_line
			(start -0.299974 -0.150114)
			(end 0.299974 -0.150114)
			(stroke
				(width 0.1)
				(type default)
			)
			(layer "F.Fab")
		)
		(fp_line
			(start 0.299974 -0.150114)
			(end 0.299974 0.150114)
			(stroke
				(width 0.1)
				(type default)
			)
			(layer "F.Fab")
		)
		(pad "1" smd rect
			(at -0.2667 0 270)
			(size 0.3048 0.381)
			(layers "F.Cu" "F.Mask" "F.Paste")
			(net "P5E_CPU1_P0_TX_C_DP<2>")
		)
		(pad "2" smd rect
			(at 0.2667 0 270)
			(size 0.3048 0.381)
			(layers "F.Cu" "F.Mask" "F.Paste")
			(net "P5E_CPU1_P0_TX_DP<2>")
		)
	)
	(footprint ""
		(layer "F.Cu")
		(at 239.152684 -57.41289)
		(property "Reference" "C1990"
			(at 0 0 0)
			(layer "F.SilkS")
			(hide yes)
			(effects
				(font
					(size 1.27 1.27)
				)
			)
		)
		(property "Value" ""
			(at 0 0 0)
			(layer "F.Fab")
			(effects
				(font
					(size 1.27 1.27)
				)
			)
		)
		(duplicate_pad_numbers_are_jumpers no)
		(fp_line
			(start -0.299974 -0.150114)
			(end 0.299974 -0.150114)
			(stroke
				(width 0.1)
				(type default)
			)
			(layer "F.Fab")
		)
		(fp_line
			(start -0.299974 0.150114)
			(end -0.299974 -0.150114)
			(stroke
				(width 0.1)
				(type default)
			)
			(layer "F.Fab")
		)
		(fp_line
			(start 0.299974 -0.150114)
			(end 0.299974 0.150114)
			(stroke
				(width 0.1)
				(type default)
			)
			(layer "F.Fab")
		)
		(fp_line
			(start 0.299974 0.150114)
			(end -0.299974 0.150114)
			(stroke
				(width 0.1)
				(type default)
			)
			(layer "F.Fab")
		)
		(pad "1" smd rect
			(at -0.2667 0)
			(size 0.3048 0.381)
			(layers "F.Cu" "F.Mask" "F.Paste")
			(net "P3E_CPU0_P4_TX_C_DN<3>")
		)
		(pad "2" smd rect
			(at 0.2667 0)
			(size 0.3048 0.381)
			(layers "F.Cu" "F.Mask" "F.Paste")
			(net "P3E_CPU0_P4_TX_DN<3>")
		)
	)
)
